# T6G (Grand Teton) — schematic netlist excerpt (pin names and nets, part order shuffled) for the footprints in the layout excerpt that follows; sources: Cadence DE-HDL packaged netlist, KiCad conversion of 04192023_DAF0TMB3IC0_F0TG_MB_C_brd_V02_OCP.brd

R1409  Q_RES  4.7K 5% CHIP  pkg 0201LF  page 309 : A = JTAG_TCK_RT_CPU0_P3 ; B = GND
PR452  Q_RES  6.98K 1% CHIP  pkg 0402LF  page 192 : A = PVDD_33_S5_CS ; B = GND
R1360  Q_RES  0 5% CHIP  pkg 0402LF  page 357 : A = INA230_7_A0 ; B = SMB_INA230_7_3V3AUX_SCL_R1

(kicad_pcb
	(version 20260206)
	(generator "pcbnew")
	(generator_version "10.0")
	(general
		(thickness 1.6)
		(legacy_teardrops no)
	)
	(paper "A4")
	(title_block
		(title "04192023_DAF0TMB3IC0_F0TG_MB_C_brd_V02_OCP.brd")
		(comment 1 "Grand Teton / footprints 1633-1635 of 8354")
	)
	(layers
		(0 "F.Cu" signal "TOP")
		(4 "In1.Cu" signal "GND")
		(6 "In2.Cu" signal "IN1")
		(8 "In3.Cu" signal "GND1")
		(10 "In4.Cu" signal "IN2")
		(12 "In5.Cu" signal "GND2")
		(14 "In6.Cu" signal "IN3")
		(16 "In7.Cu" signal "GND3")
		(18 "In8.Cu" signal "VCC")
		(20 "In9.Cu" signal "VCC1")
		(22 "In10.Cu" signal "GND4")
		(24 "In11.Cu" signal "IN4")
		(26 "In12.Cu" signal "GND5")
		(28 "In13.Cu" signal "IN5")
		(30 "In14.Cu" signal "GND6")
		(32 "In15.Cu" signal "IN6")
		(34 "In16.Cu" signal "GND7")
		(2 "B.Cu" signal "BOTTOM")
		(9 "F.Adhes" user "F.Adhesive")
		(11 "B.Adhes" user "B.Adhesive")
		(13 "F.Paste" user "Package Geometry/Pastemask Top")
		(15 "B.Paste" user "Package Geometry/Pastemask Bottom")
		(5 "F.SilkS" user "Ref Des/Silkscreen Top")
		(7 "B.SilkS" user "Ref Des/Silkscreen Bottom")
		(1 "F.Mask" user "Board Geometry/Soldermask Top")
		(3 "B.Mask" user "Board Geometry/Soldermask Bottom")
		(17 "Dwgs.User" user "User.Drawings")
		(19 "Cmts.User" user "User.Comments")
		(21 "Eco1.User" user "User.Eco1")
		(23 "Eco2.User" user "User.Eco2")
		(25 "Edge.Cuts" user "Board Geometry/Outline")
		(27 "Margin" user)
		(31 "F.CrtYd" user "Package Geometry/Place Bound Top")
		(29 "B.CrtYd" user "Package Geometry/Place Bound Bottom")
		(35 "F.Fab" user "Ref Des/Assembly Top")
		(33 "B.Fab" user "Ref Des/Assembly Bottom")
	)
	(footprint ""
		(layer "F.Cu")
		(at 204.689456 -339.428836)
		(property "Reference" "PR452"
			(at 0 0 0)
			(layer "F.SilkS")
			(hide yes)
			(effects
				(font
					(size 1.27 1.27)
				)
			)
		)
		(property "Value" ""
			(at 0 0 0)
			(layer "F.Fab")
			(effects
				(font
					(size 1.27 1.27)
				)
			)
		)
		(duplicate_pad_numbers_are_jumpers no)
		(fp_line
			(start -0.7874 -0.4064)
			(end 0.7874 -0.4064)
			(stroke
				(width 0.1524)
				(type default)
			)
			(layer "F.SilkS")
		)
		(fp_line
			(start -0.7874 0.4064)
			(end -0.7874 -0.4064)
			(stroke
				(width 0.1524)
				(type default)
			)
			(layer "F.SilkS")
		)
		(fp_line
			(start 0.7874 -0.4064)
			(end 0.7874 0.4064)
			(stroke
				(width 0.1524)
				(type default)
			)
			(layer "F.SilkS")
		)
		(fp_line
			(start 0.7874 0.4064)
			(end -0.7874 0.4064)
			(stroke
				(width 0.1524)
				(type default)
			)
			(layer "F.SilkS")
		)
		(fp_line
			(start -0.67945 -0.305054)
			(end -0.12065 -0.305054)
			(stroke
				(width 0.1)
				(type default)
			)
			(layer "F.Fab")
		)
		(fp_line
			(start -0.67945 0.3048)
			(end -0.67945 -0.305054)
			(stroke
				(width 0.1)
				(type default)
			)
			(layer "F.Fab")
		)
		(fp_line
			(start -0.12065 -0.305054)
			(end -0.12065 -0.2794)
			(stroke
				(width 0.1)
				(type default)
			)
			(layer "F.Fab")
		)
		(fp_line
			(start -0.12065 -0.2794)
			(end 0.12065 -0.2794)
			(stroke
				(width 0.1)
				(type default)
			)
			(layer "F.Fab")
		)
		(fp_line
			(start -0.12065 0.2794)
			(end -0.12065 0.3048)
			(stroke
				(width 0.1)
				(type default)
			)
			(layer "F.Fab")
		)
		(fp_line
			(start -0.12065 0.3048)
			(end -0.67945 0.3048)
			(stroke
				(width 0.1)
				(type default)
			)
			(layer "F.Fab")
		)
		(fp_line
			(start 0.120396 0.2794)
			(end -0.12065 0.2794)
			(stroke
				(width 0.1)
				(type default)
			)
			(layer "F.Fab")
		)
		(fp_line
			(start 0.120396 0.3048)
			(end 0.120396 0.2794)
			(stroke
				(width 0.1)
				(type default)
			)
			(layer "F.Fab")
		)
		(fp_line
			(start 0.12065 -0.3048)
			(end 0.67945 -0.3048)
			(stroke
				(width 0.1)
				(type default)
			)
			(layer "F.Fab")
		)
		(fp_line
			(start 0.12065 -0.2794)
			(end 0.12065 -0.3048)
			(stroke
				(width 0.1)
				(type default)
			)
			(layer "F.Fab")
		)
		(fp_line
			(start 0.67945 -0.3048)
			(end 0.67945 0.3048)
			(stroke
				(width 0.1)
				(type default)
			)
			(layer "F.Fab")
		)
		(fp_line
			(start 0.67945 0.3048)
			(end 0.120396 0.3048)
			(stroke
				(width 0.1)
				(type default)
			)
			(layer "F.Fab")
		)
		(pad "1" smd circle
			(at -0.40005 0)
			(size 0 0)
			(layers "F.Cu" "F.Mask" "F.Paste")
			(net "PVDD_33_S5_CS")
		)
		(pad "2" smd circle
			(at 0.40005 0)
			(size 0 0)
			(layers "F.Cu" "F.Mask" "F.Paste")
			(net "GND")
		)
	)
	(footprint ""
		(layer "F.Cu")
		(at 424.5356 -423.2402 90)
		(property "Reference" "R1409"
			(at 0 0 90)
			(layer "F.SilkS")
			(hide yes)
			(effects
				(font
					(size 1.27 1.27)
				)
			)
		)
		(property "Value" ""
			(at 0 0 90)
			(layer "F.Fab")
			(effects
				(font
					(size 1.27 1.27)
				)
			)
		)
		(duplicate_pad_numbers_are_jumpers no)
		(fp_line
			(start 0.32512 -0.175006)
			(end 0.32512 0.175006)
			(stroke
				(width 0.1)
				(type default)
			)
			(layer "F.Fab")
		)
		(fp_line
			(start -0.32512 -0.175006)
			(end 0.32512 -0.175006)
			(stroke
				(width 0.1)
				(type default)
			)
			(layer "F.Fab")
		)
		(fp_line
			(start 0.32512 0.175006)
			(end -0.32512 0.175006)
			(stroke
				(width 0.1)
				(type default)
			)
			(layer "F.Fab")
		)
		(fp_line
			(start -0.32512 0.175006)
			(end -0.32512 -0.175006)
			(stroke
				(width 0.1)
				(type default)
			)
			(layer "F.Fab")
		)
		(pad "1" smd rect
			(at -0.2667 0 90)
			(size 0.3048 0.381)
			(layers "F.Cu" "F.Mask" "F.Paste")
			(net "JTAG_TCK_RT_CPU0_P3")
		)
		(pad "2" smd rect
			(at 0.2667 0 270)
			(size 0.3048 0.381)
			(layers "F.Cu" "F.Mask" "F.Paste")
			(net "GND")
		)
	)
	(footprint ""
		(layer "F.Cu")
		(at 19.241516 -38.910514 180)
		(property "Reference" "R1360"
			(at 0 0 180)
			(layer "F.SilkS")
			(hide yes)
			(effects
				(font
					(size 1.27 1.27)
				)
			)
		)
		(property "Value" ""
			(at 0 0 180)
			(layer "F.Fab")
			(effects
				(font
					(size 1.27 1.27)
				)
			)
		)
		(duplicate_pad_numbers_are_jumpers no)
		(fp_line
			(start 0.7874 0.4064)
			(end -0.7874 0.4064)
			(stroke
				(width 0.1524)
				(type default)
			)
			(layer "F.SilkS")
		)
		(fp_line
			(start 0.7874 -0.4064)
			(end 0.7874 0.4064)
			(stroke
				(width 0.1524)
				(type default)
			)
			(layer "F.SilkS")
		)
		(fp_line
			(start -0.7874 0.4064)
			(end -0.7874 -0.4064)
			(stroke
				(width 0.1524)
				(type default)
			)
			(layer "F.SilkS")
		)
		(fp_line
			(start -0.7874 -0.4064)
			(end 0.7874 -0.4064)
			(stroke
				(width 0.1524)
				(type default)
			)
			(layer "F.SilkS")
		)
		(fp_line
			(start 0.67945 0.3048)
			(end 0.120396 0.3048)
			(stroke
				(width 0.1)
				(type default)
			)
			(layer "F.Fab")
		)
		(fp_line
			(start 0.67945 -0.3048)
			(end 0.67945 0.3048)
			(stroke
				(width 0.1)
				(type default)
			)
			(layer "F.Fab")
		)
		(fp_line
			(start 0.12065 -0.2794)
			(end 0.12065 -0.3048)
			(stroke
				(width 0.1)
				(type default)
			)
			(layer "F.Fab")
		)
		(fp_line
			(start 0.12065 -0.3048)
			(end 0.67945 -0.3048)
			(stroke
				(width 0.1)
				(type default)
			)
			(layer "F.Fab")
		)
		(fp_line
			(start 0.120396 0.3048)
			(end 0.120396 0.2794)
			(stroke
				(width 0.1)
				(type default)
			)
			(layer "F.Fab")
		)
		(fp_line
			(start 0.120396 0.2794)
			(end -0.12065 0.2794)
			(stroke
				(width 0.1)
				(type default)
			)
			(layer "F.Fab")
		)
		(fp_line
			(start -0.12065 0.3048)
			(end -0.67945 0.3048)
			(stroke
				(width 0.1)
				(type default)
			)
			(layer "F.Fab")
		)
		(fp_line
			(start -0.12065 0.2794)
			(end -0.12065 0.3048)
			(stroke
				(width 0.1)
				(type default)
			)
			(layer "F.Fab")
		)
		(fp_line
			(start -0.12065 -0.2794)
			(end 0.12065 -0.2794)
			(stroke
				(width 0.1)
				(type default)
			)
			(layer "F.Fab")
		)
		(fp_line
			(start -0.12065 -0.305054)
			(end -0.12065 -0.2794)
			(stroke
				(width 0.1)
				(type default)
			)
			(layer "F.Fab")
		)
		(fp_line
			(start -0.67945 0.3048)
			(end -0.67945 -0.305054)
			(stroke
				(width 0.1)
				(type default)
			)
			(layer "F.Fab")
		)
		(fp_line
			(start -0.67945 -0.305054)
			(end -0.12065 -0.305054)
			(stroke
				(width 0.1)
				(type default)
			)
			(layer "F.Fab")
		)
		(pad "1" smd circle
			(at -0.40005 0 180)
			(size 0 0)
			(layers "F.Cu" "F.Mask" "F.Paste")
			(net "INA230_7_A0")
		)
		(pad "2" smd circle
			(at 0.40005 0 180)
			(size 0 0)
			(layers "F.Cu" "F.Mask" "F.Paste")
			(net "SMB_INA230_7_3V3AUX_SCL_R1")
		)
	)
)
